# S9S_MB_2U (Grand Teton) — schematic netlist excerpt (pin names and nets, part order shuffled) for the footprints in the layout excerpt that follows; sources: Cadence DE-HDL packaged netlist, KiCad conversion of 03242023_DA0F0TMBIJ0_F0T_Motherboard_J_brd_V01_OCP.brd

C2371  Q_CAP  0.1UF 25V 10% EMPTY  pkg 0402  page 245 : A = FM_AC_PWR_BTN_PDB_N ; B = GND
C29  Q_CAP  2.2UF 6.3V 20% X6S  pkg C0402  page 91 : A = P3V3_AUX ; B = GND
PC1255  Q_CAP  22UF 4V 20% X6S  pkg C0805  page 281 : A = PVPP_HBM_CPU0 ; B = GND

(kicad_pcb
	(version 20260206)
	(generator "pcbnew")
	(generator_version "10.0")
	(general
		(thickness 1.6)
		(legacy_teardrops no)
	)
	(paper "A4")
	(title_block
		(title "03242023_DA0F0TMBIJ0_F0T_Motherboard_J_brd_V01_OCP.brd")
		(comment 1 "Grand Teton / footprints 5884-5886 of 6105")
	)
	(layers
		(0 "F.Cu" signal "TOP")
		(4 "In1.Cu" signal "GND")
		(6 "In2.Cu" signal "IN1")
		(8 "In3.Cu" signal "GND1")
		(10 "In4.Cu" signal "IN2")
		(12 "In5.Cu" signal "GND2")
		(14 "In6.Cu" signal "IN3")
		(16 "In7.Cu" signal "GND3")
		(18 "In8.Cu" signal "VCC")
		(20 "In9.Cu" signal "VCC1")
		(22 "In10.Cu" signal "GND4")
		(24 "In11.Cu" signal "IN4")
		(26 "In12.Cu" signal "GND5")
		(28 "In13.Cu" signal "IN5")
		(30 "In14.Cu" signal "GND6")
		(32 "In15.Cu" signal "IN6")
		(34 "In16.Cu" signal "GND7")
		(2 "B.Cu" signal "BOTTOM")
		(9 "F.Adhes" user "F.Adhesive")
		(11 "B.Adhes" user "B.Adhesive")
		(13 "F.Paste" user "Package Geometry/Pastemask Top")
		(15 "B.Paste" user "Package Geometry/Pastemask Bottom")
		(5 "F.SilkS" user "Ref Des/Silkscreen Top")
		(7 "B.SilkS" user "Ref Des/Silkscreen Bottom")
		(1 "F.Mask" user "Board Geometry/Soldermask Top")
		(3 "B.Mask" user "Board Geometry/Soldermask Bottom")
		(17 "Dwgs.User" user "User.Drawings")
		(19 "Cmts.User" user "User.Comments")
		(21 "Eco1.User" user "User.Eco1")
		(23 "Eco2.User" user "User.Eco2")
		(25 "Edge.Cuts" user "Board Geometry/Outline")
		(27 "Margin" user)
		(31 "F.CrtYd" user "Package Geometry/Place Bound Top")
		(29 "B.CrtYd" user "Package Geometry/Place Bound Bottom")
		(35 "F.Fab" user "Ref Des/Assembly Top")
		(33 "B.Fab" user "Ref Des/Assembly Bottom")
	)
	(footprint ""
		(layer "B.Cu")
		(at 407.0731 -319.080642 90)
		(property "Reference" "C29"
			(at 0 0 90)
			(layer "B.SilkS")
			(hide yes)
			(effects
				(font
					(size 1.27 1.27)
				)
				(justify mirror)
			)
		)
		(property "Value" ""
			(at 0 0 90)
			(layer "B.Fab")
			(effects
				(font
					(size 1.27 1.27)
				)
				(justify mirror)
			)
		)
		(duplicate_pad_numbers_are_jumpers no)
		(fp_line
			(start 0.7874 -0.4064)
			(end -0.7874 -0.4064)
			(stroke
				(width 0.1524)
				(type default)
			)
			(layer "B.SilkS")
		)
		(fp_line
			(start -0.7874 -0.4064)
			(end -0.7874 0.4064)
			(stroke
				(width 0.1524)
				(type default)
			)
			(layer "B.SilkS")
		)
		(fp_line
			(start 0.7874 0.4064)
			(end 0.7874 -0.4064)
			(stroke
				(width 0.1524)
				(type default)
			)
			(layer "B.SilkS")
		)
		(fp_line
			(start -0.7874 0.4064)
			(end 0.7874 0.4064)
			(stroke
				(width 0.1524)
				(type default)
			)
			(layer "B.SilkS")
		)
		(fp_line
			(start 0.67945 -0.305054)
			(end 0.12065 -0.305054)
			(stroke
				(width 0.1)
				(type default)
			)
			(layer "B.Fab")
		)
		(fp_line
			(start 0.12065 -0.305054)
			(end 0.12065 -0.2794)
			(stroke
				(width 0.1)
				(type default)
			)
			(layer "B.Fab")
		)
		(fp_line
			(start -0.12065 -0.3048)
			(end -0.67945 -0.3048)
			(stroke
				(width 0.1)
				(type default)
			)
			(layer "B.Fab")
		)
		(fp_line
			(start -0.67945 -0.3048)
			(end -0.67945 0.3048)
			(stroke
				(width 0.1)
				(type default)
			)
			(layer "B.Fab")
		)
		(fp_line
			(start 0.12065 -0.2794)
			(end -0.12065 -0.2794)
			(stroke
				(width 0.1)
				(type default)
			)
			(layer "B.Fab")
		)
		(fp_line
			(start -0.12065 -0.2794)
			(end -0.12065 -0.3048)
			(stroke
				(width 0.1)
				(type default)
			)
			(layer "B.Fab")
		)
		(fp_line
			(start 0.12065 0.2794)
			(end 0.12065 0.3048)
			(stroke
				(width 0.1)
				(type default)
			)
			(layer "B.Fab")
		)
		(fp_line
			(start -0.120396 0.2794)
			(end 0.12065 0.2794)
			(stroke
				(width 0.1)
				(type default)
			)
			(layer "B.Fab")
		)
		(fp_line
			(start 0.67945 0.3048)
			(end 0.67945 -0.305054)
			(stroke
				(width 0.1)
				(type default)
			)
			(layer "B.Fab")
		)
		(fp_line
			(start 0.12065 0.3048)
			(end 0.67945 0.3048)
			(stroke
				(width 0.1)
				(type default)
			)
			(layer "B.Fab")
		)
		(fp_line
			(start -0.120396 0.3048)
			(end -0.120396 0.2794)
			(stroke
				(width 0.1)
				(type default)
			)
			(layer "B.Fab")
		)
		(fp_line
			(start -0.67945 0.3048)
			(end -0.120396 0.3048)
			(stroke
				(width 0.1)
				(type default)
			)
			(layer "B.Fab")
		)
		(pad "1" smd circle
			(at 0.40005 0 270)
			(size 0 0)
			(layers "B.Cu" "B.Mask" "B.Paste")
			(net "P3V3_AUX")
		)
		(pad "2" smd circle
			(at -0.40005 0 270)
			(size 0 0)
			(layers "B.Cu" "B.Mask" "B.Paste")
			(net "GND")
		)
	)
	(footprint ""
		(layer "B.Cu")
		(at 233.2482 -423.0116 90)
		(property "Reference" "C2371"
			(at 0 0 90)
			(layer "B.SilkS")
			(hide yes)
			(effects
				(font
					(size 1.27 1.27)
				)
				(justify mirror)
			)
		)
		(property "Value" ""
			(at 0 0 90)
			(layer "B.Fab")
			(effects
				(font
					(size 1.27 1.27)
				)
				(justify mirror)
			)
		)
		(duplicate_pad_numbers_are_jumpers no)
		(fp_line
			(start 0.7874 -0.4064)
			(end -0.7874 -0.4064)
			(stroke
				(width 0.1524)
				(type default)
			)
			(layer "B.SilkS")
		)
		(fp_line
			(start -0.7874 -0.4064)
			(end -0.7874 0.4064)
			(stroke
				(width 0.1524)
				(type default)
			)
			(layer "B.SilkS")
		)
		(fp_line
			(start 0.7874 0.4064)
			(end 0.7874 -0.4064)
			(stroke
				(width 0.1524)
				(type default)
			)
			(layer "B.SilkS")
		)
		(fp_line
			(start -0.7874 0.4064)
			(end 0.7874 0.4064)
			(stroke
				(width 0.1524)
				(type default)
			)
			(layer "B.SilkS")
		)
		(fp_line
			(start 0.67945 -0.305054)
			(end 0.12065 -0.305054)
			(stroke
				(width 0.1)
				(type default)
			)
			(layer "B.Fab")
		)
		(fp_line
			(start 0.12065 -0.305054)
			(end 0.12065 -0.2794)
			(stroke
				(width 0.1)
				(type default)
			)
			(layer "B.Fab")
		)
		(fp_line
			(start -0.12065 -0.3048)
			(end -0.67945 -0.3048)
			(stroke
				(width 0.1)
				(type default)
			)
			(layer "B.Fab")
		)
		(fp_line
			(start -0.67945 -0.3048)
			(end -0.67945 0.3048)
			(stroke
				(width 0.1)
				(type default)
			)
			(layer "B.Fab")
		)
		(fp_line
			(start 0.12065 -0.2794)
			(end -0.12065 -0.2794)
			(stroke
				(width 0.1)
				(type default)
			)
			(layer "B.Fab")
		)
		(fp_line
			(start -0.12065 -0.2794)
			(end -0.12065 -0.3048)
			(stroke
				(width 0.1)
				(type default)
			)
			(layer "B.Fab")
		)
		(fp_line
			(start 0.12065 0.2794)
			(end 0.12065 0.3048)
			(stroke
				(width 0.1)
				(type default)
			)
			(layer "B.Fab")
		)
		(fp_line
			(start -0.120396 0.2794)
			(end 0.12065 0.2794)
			(stroke
				(width 0.1)
				(type default)
			)
			(layer "B.Fab")
		)
		(fp_line
			(start 0.67945 0.3048)
			(end 0.67945 -0.305054)
			(stroke
				(width 0.1)
				(type default)
			)
			(layer "B.Fab")
		)
		(fp_line
			(start 0.12065 0.3048)
			(end 0.67945 0.3048)
			(stroke
				(width 0.1)
				(type default)
			)
			(layer "B.Fab")
		)
		(fp_line
			(start -0.120396 0.3048)
			(end -0.120396 0.2794)
			(stroke
				(width 0.1)
				(type default)
			)
			(layer "B.Fab")
		)
		(fp_line
			(start -0.67945 0.3048)
			(end -0.120396 0.3048)
			(stroke
				(width 0.1)
				(type default)
			)
			(layer "B.Fab")
		)
		(pad "1" smd circle
			(at 0.40005 0 270)
			(size 0 0)
			(layers "B.Cu" "B.Mask" "B.Paste")
			(net "FM_AC_PWR_BTN_PDB_N")
		)
		(pad "2" smd circle
			(at -0.40005 0 270)
			(size 0 0)
			(layers "B.Cu" "B.Mask" "B.Paste")
			(net "GND")
		)
	)
	(footprint ""
		(layer "B.Cu")
		(at 375.943876 -366.755426 90)
		(property "Reference" "PC1255"
			(at 0 0 90)
			(layer "B.SilkS")
			(hide yes)
			(effects
				(font
					(size 1.27 1.27)
				)
				(justify mirror)
			)
		)
		(property "Value" ""
			(at 0 0 90)
			(layer "B.Fab")
			(effects
				(font
					(size 1.27 1.27)
				)
				(justify mirror)
			)
		)
		(duplicate_pad_numbers_are_jumpers no)
		(fp_line
			(start 1.524 -0.762)
			(end -1.524 -0.762)
			(stroke
				(width 0.1524)
				(type default)
			)
			(layer "B.SilkS")
		)
		(fp_line
			(start -1.524 -0.762)
			(end -1.524 0.762)
			(stroke
				(width 0.1524)
				(type default)
			)
			(layer "B.SilkS")
		)
		(fp_line
			(start 1.524 0.762)
			(end 1.524 -0.762)
			(stroke
				(width 0.1524)
				(type default)
			)
			(layer "B.SilkS")
		)
		(fp_line
			(start -1.524 0.762)
			(end 1.524 0.762)
			(stroke
				(width 0.1524)
				(type default)
			)
			(layer "B.SilkS")
		)
		(fp_line
			(start 1.1049 -0.724916)
			(end 1.1049 0.724916)
			(stroke
				(width 0.1)
				(type default)
			)
			(layer "B.Fab")
		)
		(fp_line
			(start -1.1049 -0.724916)
			(end 1.1049 -0.724916)
			(stroke
				(width 0.1)
				(type default)
			)
			(layer "B.Fab")
		)
		(fp_line
			(start 1.1049 0.724916)
			(end -1.1049 0.724916)
			(stroke
				(width 0.1)
				(type default)
			)
			(layer "B.Fab")
		)
		(fp_line
			(start -1.1049 0.724916)
			(end -1.1049 -0.724916)
			(stroke
				(width 0.1)
				(type default)
			)
			(layer "B.Fab")
		)
		(pad "1" smd rect
			(at 0.889 0 90)
			(size 1.016 1.27)
			(layers "B.Cu" "B.Mask" "B.Paste")
			(net "PVPP_HBM_CPU0")
		)
		(pad "2" smd rect
			(at -0.889 0 90)
			(size 1.016 1.27)
			(layers "B.Cu" "B.Mask" "B.Paste")
			(net "GND")
		)
	)
)
